#ISCELL
  mstr_symbols cad_note *
  *
#ISCELL
  mstr_symbols design_note *
  *
#ISCELL
  mstr_symbols intel_corp_bpage *
  *
#CELL
  dev_discrete cap_a *
  page130_i12
#ISCELL
  mstr_symbols gnd *
  page130_i13
#ISCELL
  mstr_symbols gnd *
  page130_i14
#CELL
  mstr_discrete cap *
  page130_i15
#CELL
  dev_discrete cap_a *
  page130_i16
#ISCELL
  mstr_symbols gnd *
  page130_i17
#ISCELL
  mstr_standard offpage *
  page130_i18
#CELL
  mstr_discrete cap *
  page130_i19
#CELL
  mstr_discrete cap *
  page130_i2
#CELL
  mstr_discrete cap *
  page130_i20
#CELL
  mstr_discrete cap *
  page130_i21
#CELL
  mstr_discrete cap *
  page130_i22
#CELL
  mstr_discrete cap *
  page130_i24
#CELL
  mstr_discrete cap *
  page130_i25
#ISCELL
  mstr_symbols gnd *
  page130_i27
#CELL
  mstr_discrete cap *
  page130_i28
#CELL
  dev_discrete cap_a *
  page130_i29
#ISCELL
  mstr_symbols gnd *
  page130_i3
#CELL
  dev_discrete cap_a *
  page130_i30
#ISCELL
  mstr_symbols p1v8_pch_stby *
  page130_i31
#CELL
  dev_discrete cap_a *
  page130_i32
#ISCELL
  mstr_symbols gnd *
  page130_i33
#CELL
  dev_discrete cap_a *
  page130_i34
#ISCELL
  mstr_symbols gnd *
  page130_i35
#CELL
  dev_discrete cap_a *
  page130_i37
#CELL
  dev_discrete cap_a *
  page130_i38
#CELL
  dev_discrete cap_a *
  page130_i39
#CELL
  dev_discrete cap_a *
  page130_i4
#ISCELL
  mstr_symbols gnd *
  page130_i40
#CELL
  dev_discrete cap_a *
  page130_i41
#CELL
  dev_discrete cap_a *
  page130_i42
#CELL
  dev_discrete cap_a *
  page130_i43
#ISCELL
  mstr_symbols p1v8_pch_stby *
  page130_i44
#CELL
  dev_discrete cap_a *
  page130_i45
#ISCELL
  mstr_symbols gnd *
  page130_i46
#CELL
  dev_discrete cap_a *
  page130_i47
#ISCELL
  mstr_symbols gnd *
  page130_i48
#CELL
  dev_discrete cap_a *
  page130_i49
#CELL
  dev_discrete cap_a *
  page130_i50
#ISCELL
  mstr_symbols p1v8_pch_stby *
  page130_i51
#CELL
  dev_discrete cap_a *
  page130_i52
#CELL
  dev_discrete cap_a *
  page130_i53
#ISCELL
  mstr_symbols p3v3_stby *
  page130_i54
#ISCELL
  mstr_symbols p3v3_stby *
  page130_i55
#ISCELL
  mstr_symbols p3v3_stby *
  page130_i58
#ISCELL
  mstr_symbols p3v3_stby *
  page130_i59
#ISCELL
  mstr_symbols gnd *
  page130_i6
#ISCELL
  mstr_symbols p3v3_stby *
  page130_i60
#ISCELL
  mstr_symbols p3v3_stby *
  page130_i61
#ISCELL
  mstr_symbols p3v3_stby *
  page130_i62
#CELL
  dev_discrete cap_a *
  page130_i7
#CELL
  mstr_discrete cap *
  page130_i8
#CELL
  mstr_discrete cap *
  page130_i9
